(kicad_pcb
	(version 20241229)
	(generator "pcbnew")
	(generator_version "9.0")
	(general
		(thickness 1.294)
		(legacy_teardrops no)
	)
	(paper "A3")
	(title_block
		(title "Kintex 410T devboard")
		(date "2024-04-03")
		(rev "1.1.2")
		(comment 9 "footprints 223-223 of 975")
	)
	(layers
		(0 "F.Cu" mixed)
		(4 "In1.Cu" power)
		(6 "In2.Cu" power)
		(8 "In3.Cu" mixed)
		(10 "In4.Cu" power)
		(12 "In5.Cu" mixed)
		(14 "In6.Cu" power)
		(16 "In7.Cu" mixed)
		(18 "In8.Cu" power)
		(2 "B.Cu" mixed)
		(9 "F.Adhes" user "F.Adhesive")
		(11 "B.Adhes" user "B.Adhesive")
		(13 "F.Paste" user)
		(15 "B.Paste" user)
		(5 "F.SilkS" user "F.Silkscreen")
		(7 "B.SilkS" user "B.Silkscreen")
		(1 "F.Mask" user)
		(3 "B.Mask" user)
		(17 "Dwgs.User" user "User.Drawings")
		(19 "Cmts.User" user "User.Comments")
		(21 "Eco1.User" user "User.Eco1")
		(23 "Eco2.User" user "User.Eco2")
		(25 "Edge.Cuts" user)
		(27 "Margin" user)
		(31 "F.CrtYd" user "F.Courtyard")
		(29 "B.CrtYd" user "B.Courtyard")
		(35 "F.Fab" user)
		(33 "B.Fab" user)
	)
	(footprint "antmicro-footprints:C_0402_1005Metric"
		(layer "F.Cu")
		(at 240.55 140.2 180)
		(descr "Capacitor SMD 0402")
		(tags "capacitor SMD 0402")
		(property "Reference" "C247"
			(at 0.4 -1.3 180)
			(layer "F.SilkS")
			(effects
				(font
					(size 0.7 0.7)
					(thickness 0.15)
				)
				(justify left bottom)
			)
		)
		(property "Value" "C_100n_0402"
			(at 0 1.169 180)
			(layer "F.Fab")
			(effects
				(font
					(size 0.7 0.7)
					(thickness 0.15)
				)
				(justify left bottom)
			)
		)
		(property "Description" "SMD Multilayer Ceramic Capacitor, 0.1 µF, 50 V, 0402 [1005 Metric], ± 10%, X5R, GRM Series"
			(at 0 0 180)
			(layer "F.Fab")
			(hide yes)
			(effects
				(font
					(size 1.27 1.27)
					(thickness 0.15)
				)
			)
		)
		(property "Author" "Antmicro"
			(at 481.1 280.4 0)
			(layer "F.Fab")
			(hide yes)
			(effects
				(font
					(size 1 1)
					(thickness 0.15)
				)
			)
		)
		(property "Dielectric" "X5R"
			(at 481.1 280.4 0)
			(layer "F.Fab")
			(hide yes)
			(effects
				(font
					(size 1 1)
					(thickness 0.15)
				)
			)
		)
		(property "License" "Apache-2.0"
			(at 481.1 280.4 0)
			(layer "F.Fab")
			(hide yes)
			(effects
				(font
					(size 1 1)
					(thickness 0.15)
				)
			)
		)
		(property "MPN" "GRM155R61H104KE14D"
			(at 481.1 280.4 0)
			(layer "F.Fab")
			(hide yes)
			(effects
				(font
					(size 1 1)
					(thickness 0.15)
				)
			)
		)
		(property "Manufacturer" "Murata"
			(at 481.1 280.4 0)
			(layer "F.Fab")
			(hide yes)
			(effects
				(font
					(size 1 1)
					(thickness 0.15)
				)
			)
		)
		(property "Val" "100n"
			(at 481.1 280.4 0)
			(layer "F.Fab")
			(hide yes)
			(effects
				(font
					(size 1 1)
					(thickness 0.15)
				)
			)
		)
		(property "Voltage" "50V"
			(at 481.1 280.4 0)
			(layer "F.Fab")
			(hide yes)
			(effects
				(font
					(size 1 1)
					(thickness 0.15)
				)
			)
		)
		(sheetname "USB PHY")
		(sheetfile "usb-phy.kicad_sch")
		(attr smd)
		(fp_rect
			(start -0.925 -0.47)
			(end 0.925 0.47)
			(stroke
				(width 0.05)
				(type default)
			)
			(fill no)
			(layer "F.CrtYd")
		)
		(fp_line
			(start 0.504 0.248)
			(end -0.494 0.248)
			(stroke
				(width 0.15)
				(type solid)
			)
			(layer "F.Fab")
		)
		(fp_line
			(start 0.504 -0.25)
			(end 0.504 0.248)
			(stroke
				(width 0.15)
				(type solid)
			)
			(layer "F.Fab")
		)
		(fp_line
			(start -0.494 0.248)
			(end -0.494 -0.25)
			(stroke
				(width 0.15)
				(type solid)
			)
			(layer "F.Fab")
		)
		(fp_line
			(start -0.494 -0.25)
			(end 0.504 -0.25)
			(stroke
				(width 0.15)
				(type solid)
			)
			(layer "F.Fab")
		)
		(pad "1" smd roundrect
			(at -0.48 0 180)
			(size 0.59 0.64)
			(layers "F.Cu" "F.Mask" "F.Paste")
			(roundrect_rratio 0.25)
			(net 1 "GND")
			(pintype "passive")
		)
		(pad "2" smd roundrect
			(at 0.48 0 180)
			(size 0.59 0.64)
			(layers "F.Cu" "F.Mask" "F.Paste")
			(roundrect_rratio 0.25)
			(net 707 "/USB PHY/FTDI_3V3")
			(pintype "passive")
		)
	)
)
